# S9S_MB_2U (Grand Teton) — schematic netlist excerpt (pin names and nets, part order shuffled) for the footprints in the layout excerpt that follows; sources: Cadence DE-HDL packaged netlist, KiCad conversion of 03242023_DA0F0TMBIJ0_F0T_Motherboard_J_brd_V01_OCP.brd

R763  Q_RES  10 1% CHIP  pkg 0402LF  page 131 : A = JTAG_DBP_TDI ; B = JTAG_DBP_TDI_R

Q130  MOSFET_NCH_DUAL  PJT138K IC  pkg SOT363XD  page 146
  S1  = GND
  G1  = GPU_3V3IO_RSVD3_FFU
  D2  = GPU_3V3IO_RSVD3_FFU_ISO
  S2  = GND
  G2  = GPU_3V3IO_RSVD3_FFU_N
  D1  = GPU_3V3IO_RSVD3_FFU_N

(kicad_pcb
	(version 20260206)
	(generator "pcbnew")
	(generator_version "10.0")
	(general
		(thickness 1.6)
		(legacy_teardrops no)
	)
	(paper "A4")
	(title_block
		(title "03242023_DA0F0TMBIJ0_F0T_Motherboard_J_brd_V01_OCP.brd")
		(comment 1 "Grand Teton / footprints 231-232 of 6105")
	)
	(layers
		(0 "F.Cu" signal "TOP")
		(4 "In1.Cu" signal "GND")
		(6 "In2.Cu" signal "IN1")
		(8 "In3.Cu" signal "GND1")
		(10 "In4.Cu" signal "IN2")
		(12 "In5.Cu" signal "GND2")
		(14 "In6.Cu" signal "IN3")
		(16 "In7.Cu" signal "GND3")
		(18 "In8.Cu" signal "VCC")
		(20 "In9.Cu" signal "VCC1")
		(22 "In10.Cu" signal "GND4")
		(24 "In11.Cu" signal "IN4")
		(26 "In12.Cu" signal "GND5")
		(28 "In13.Cu" signal "IN5")
		(30 "In14.Cu" signal "GND6")
		(32 "In15.Cu" signal "IN6")
		(34 "In16.Cu" signal "GND7")
		(2 "B.Cu" signal "BOTTOM")
		(9 "F.Adhes" user "F.Adhesive")
		(11 "B.Adhes" user "B.Adhesive")
		(13 "F.Paste" user "Package Geometry/Pastemask Top")
		(15 "B.Paste" user "Package Geometry/Pastemask Bottom")
		(5 "F.SilkS" user "Ref Des/Silkscreen Top")
		(7 "B.SilkS" user "Ref Des/Silkscreen Bottom")
		(1 "F.Mask" user "Board Geometry/Soldermask Top")
		(3 "B.Mask" user "Board Geometry/Soldermask Bottom")
		(17 "Dwgs.User" user "User.Drawings")
		(19 "Cmts.User" user "User.Comments")
		(21 "Eco1.User" user "User.Eco1")
		(23 "Eco2.User" user "User.Eco2")
		(25 "Edge.Cuts" user "Board Geometry/Outline")
		(27 "Margin" user)
		(31 "F.CrtYd" user "Package Geometry/Place Bound Top")
		(29 "B.CrtYd" user "Package Geometry/Place Bound Bottom")
		(35 "F.Fab" user "Ref Des/Assembly Top")
		(33 "B.Fab" user "Ref Des/Assembly Bottom")
	)
	(footprint ""
		(layer "F.Cu")
		(at 385.716272 -64.672464)
		(property "Reference" "R763"
			(at 0 0 0)
			(layer "F.SilkS")
			(hide yes)
			(effects
				(font
					(size 1.27 1.27)
				)
			)
		)
		(property "Value" ""
			(at 0 0 0)
			(layer "F.Fab")
			(effects
				(font
					(size 1.27 1.27)
				)
			)
		)
		(duplicate_pad_numbers_are_jumpers no)
		(fp_line
			(start -0.7874 -0.4064)
			(end 0.7874 -0.4064)
			(stroke
				(width 0.1524)
				(type default)
			)
			(layer "F.SilkS")
		)
		(fp_line
			(start -0.7874 0.4064)
			(end -0.7874 -0.4064)
			(stroke
				(width 0.1524)
				(type default)
			)
			(layer "F.SilkS")
		)
		(fp_line
			(start 0.7874 -0.4064)
			(end 0.7874 0.4064)
			(stroke
				(width 0.1524)
				(type default)
			)
			(layer "F.SilkS")
		)
		(fp_line
			(start 0.7874 0.4064)
			(end -0.7874 0.4064)
			(stroke
				(width 0.1524)
				(type default)
			)
			(layer "F.SilkS")
		)
		(fp_line
			(start -0.67945 -0.305054)
			(end -0.12065 -0.305054)
			(stroke
				(width 0.1)
				(type default)
			)
			(layer "F.Fab")
		)
		(fp_line
			(start -0.67945 0.3048)
			(end -0.67945 -0.305054)
			(stroke
				(width 0.1)
				(type default)
			)
			(layer "F.Fab")
		)
		(fp_line
			(start -0.12065 -0.305054)
			(end -0.12065 -0.2794)
			(stroke
				(width 0.1)
				(type default)
			)
			(layer "F.Fab")
		)
		(fp_line
			(start -0.12065 -0.2794)
			(end 0.12065 -0.2794)
			(stroke
				(width 0.1)
				(type default)
			)
			(layer "F.Fab")
		)
		(fp_line
			(start -0.12065 0.2794)
			(end -0.12065 0.3048)
			(stroke
				(width 0.1)
				(type default)
			)
			(layer "F.Fab")
		)
		(fp_line
			(start -0.12065 0.3048)
			(end -0.67945 0.3048)
			(stroke
				(width 0.1)
				(type default)
			)
			(layer "F.Fab")
		)
		(fp_line
			(start 0.120396 0.2794)
			(end -0.12065 0.2794)
			(stroke
				(width 0.1)
				(type default)
			)
			(layer "F.Fab")
		)
		(fp_line
			(start 0.120396 0.3048)
			(end 0.120396 0.2794)
			(stroke
				(width 0.1)
				(type default)
			)
			(layer "F.Fab")
		)
		(fp_line
			(start 0.12065 -0.3048)
			(end 0.67945 -0.3048)
			(stroke
				(width 0.1)
				(type default)
			)
			(layer "F.Fab")
		)
		(fp_line
			(start 0.12065 -0.2794)
			(end 0.12065 -0.3048)
			(stroke
				(width 0.1)
				(type default)
			)
			(layer "F.Fab")
		)
		(fp_line
			(start 0.67945 -0.3048)
			(end 0.67945 0.3048)
			(stroke
				(width 0.1)
				(type default)
			)
			(layer "F.Fab")
		)
		(fp_line
			(start 0.67945 0.3048)
			(end 0.120396 0.3048)
			(stroke
				(width 0.1)
				(type default)
			)
			(layer "F.Fab")
		)
		(pad "1" smd circle
			(at -0.40005 0)
			(size 0 0)
			(layers "F.Cu" "F.Mask" "F.Paste")
			(net "JTAG_DBP_TDI")
		)
		(pad "2" smd circle
			(at 0.40005 0)
			(size 0 0)
			(layers "F.Cu" "F.Mask" "F.Paste")
			(net "JTAG_DBP_TDI_R")
		)
	)
	(footprint ""
		(layer "F.Cu")
		(at 303.18456 -435.63667 90)
		(property "Reference" "Q130"
			(at -7.3787 -2.588768 90)
			(unlocked yes)
			(layer "F.SilkS")
			(effects
				(font
					(size 0.7874 0.5842)
					(thickness 0.1524)
				)
				(justify left)
			)
		)
		(property "Value" ""
			(at 0 0 90)
			(layer "F.Fab")
			(effects
				(font
					(size 1.27 1.27)
				)
			)
		)
		(duplicate_pad_numbers_are_jumpers no)
		(fp_line
			(start 1.332738 -1.100074)
			(end 1.332738 1.100074)
			(stroke
				(width 0.1524)
				(type default)
			)
			(layer "F.SilkS")
		)
		(fp_line
			(start 0.4826 -1.100074)
			(end 1.332738 -1.100074)
			(stroke
				(width 0.1524)
				(type default)
			)
			(layer "F.SilkS")
		)
		(fp_line
			(start -0.4826 -1.100074)
			(end 0 -0.541274)
			(stroke
				(width 0.1524)
				(type default)
			)
			(layer "F.SilkS")
		)
		(fp_line
			(start -1.332738 -1.100074)
			(end -0.4826 -1.100074)
			(stroke
				(width 0.1524)
				(type default)
			)
			(layer "F.SilkS")
		)
		(fp_line
			(start 0 -0.541274)
			(end 0.4826 -1.100074)
			(stroke
				(width 0.1524)
				(type default)
			)
			(layer "F.SilkS")
		)
		(fp_line
			(start 1.332738 1.100074)
			(end -1.332738 1.100074)
			(stroke
				(width 0.1524)
				(type default)
			)
			(layer "F.SilkS")
		)
		(fp_line
			(start -1.332738 1.100074)
			(end -1.332738 -1.100074)
			(stroke
				(width 0.1524)
				(type default)
			)
			(layer "F.SilkS")
		)
		(fp_poly
			(pts
				(xy -1.893062 -1.670558) (xy -1.644904 -0.926084) (xy -2.389378 -1.174242)
			)
			(stroke
				(width 0)
				(type default)
			)
			(fill yes)
			(layer "F.SilkS")
		)
		(fp_line
			(start 0.674878 -1.100074)
			(end 0.674878 1.100074)
			(stroke
				(width 0.1)
				(type default)
			)
			(layer "F.Fab")
		)
		(fp_line
			(start -0.674878 -1.100074)
			(end 0.674878 -1.100074)
			(stroke
				(width 0.1)
				(type default)
			)
			(layer "F.Fab")
		)
		(fp_line
			(start 0.674878 1.100074)
			(end -0.674878 1.100074)
			(stroke
				(width 0.1)
				(type default)
			)
			(layer "F.Fab")
		)
		(fp_line
			(start -0.674878 1.100074)
			(end -0.674878 -1.100074)
			(stroke
				(width 0.1)
				(type default)
			)
			(layer "F.Fab")
		)
		(fp_poly
			(pts
				(xy -2.2352 -0.298958) (xy -2.2352 -1.001014) (xy -1.533144 -0.649986)
			)
			(stroke
				(width 0)
				(type default)
			)
			(fill yes)
			(layer "F.Fab")
		)
		(pad "1" smd rect
			(at -0.94996 -0.649986 180)
			(size 0.4318 0.508)
			(layers "F.Cu" "F.Mask" "F.Paste")
			(net "GND")
		)
		(pad "2" smd rect
			(at -0.94996 0 180)
			(size 0.4318 0.508)
			(layers "F.Cu" "F.Mask" "F.Paste")
			(net "GPU_3V3IO_RSVD3_FFU")
		)
		(pad "3" smd rect
			(at -0.94996 0.649986 180)
			(size 0.4318 0.508)
			(layers "F.Cu" "F.Mask" "F.Paste")
			(net "GPU_3V3IO_RSVD3_FFU_ISO")
		)
		(pad "4" smd rect
			(at 0.94996 0.649986 180)
			(size 0.4318 0.508)
			(layers "F.Cu" "F.Mask" "F.Paste")
			(net "GND")
		)
		(pad "5" smd rect
			(at 0.94996 0 180)
			(size 0.4318 0.508)
			(layers "F.Cu" "F.Mask" "F.Paste")
			(net "GPU_3V3IO_RSVD3_FFU_N")
		)
		(pad "6" smd rect
			(at 0.94996 -0.649986 180)
			(size 0.4318 0.508)
			(layers "F.Cu" "F.Mask" "F.Paste")
			(net "GPU_3V3IO_RSVD3_FFU_N")
		)
	)
)
